(kicad_pcb
	(version 20241229)
	(generator "pcbnew")
	(generator_version "9.0")
	(general
		(thickness 1.552)
		(legacy_teardrops no)
	)
	(paper "A4")
	(title_block
		(date "2023-07-25")
		(rev "1.1.4")
		(comment 9 "footprints 373-377 of 379")
	)
	(layers
		(0 "F.Cu" signal)
		(4 "In1.Cu" signal)
		(6 "In2.Cu" signal)
		(8 "In3.Cu" signal)
		(10 "In4.Cu" signal)
		(12 "In5.Cu" signal)
		(14 "In6.Cu" signal)
		(2 "B.Cu" signal)
		(9 "F.Adhes" user "F.Adhesive")
		(11 "B.Adhes" user "B.Adhesive")
		(13 "F.Paste" user)
		(15 "B.Paste" user)
		(5 "F.SilkS" user "F.Silkscreen")
		(7 "B.SilkS" user "B.Silkscreen")
		(1 "F.Mask" user)
		(3 "B.Mask" user)
		(17 "Dwgs.User" user "User.Drawings")
		(19 "Cmts.User" user "User.Comments")
		(21 "Eco1.User" user "User.Eco1")
		(23 "Eco2.User" user "User.Eco2")
		(25 "Edge.Cuts" user)
		(27 "Margin" user)
		(31 "F.CrtYd" user "F.Courtyard")
		(29 "B.CrtYd" user "B.Courtyard")
		(35 "F.Fab" user)
		(33 "B.Fab" user)
	)
	(footprint "antmicro-footprints:C_0201"
		(layer "B.Cu")
		(at 129.9 94.7 -135)
		(descr "Capacitor SMD 0201")
		(tags "capacitor SMD 0201")
		(property "Reference" "C97"
			(at -3.553732 15.249278 45)
			(layer "B.SilkS")
			(effects
				(font
					(size 0.65 0.65)
					(thickness 0.15)
				)
				(justify left bottom mirror)
			)
		)
		(property "Value" "C_100n_0201"
			(at 0 -1.399999 45)
			(layer "B.Fab")
			(hide yes)
			(effects
				(font
					(size 0.7 0.7)
					(thickness 0.15)
				)
				(justify left bottom mirror)
			)
		)
		(property "Datasheet" "https://www.yageo.com/en/Chart/Download/pdf/CC0201KRX6S5BB104"
			(at 0 0 225)
			(layer "F.Fab")
			(hide yes)
			(effects
				(font
					(size 1.27 1.27)
					(thickness 0.15)
				)
			)
		)
		(property "Description" "SMD Multilayer Ceramic Capacitor, 0.1 µF, 6.3 V, 0201 [0603 Metric], ± 10%, X6S, CC Series"
			(at 0 0 225)
			(layer "F.Fab")
			(hide yes)
			(effects
				(font
					(size 1.27 1.27)
					(thickness 0.15)
				)
			)
		)
		(property "Author" "Antmicro"
			(at 154.790159 253.516183 0)
			(layer "B.Fab")
			(hide yes)
			(effects
				(font
					(size 1 1)
					(thickness 0.15)
				)
				(justify mirror)
			)
		)
		(property "Dielectric" ""
			(at 154.790159 253.516183 0)
			(layer "B.Fab")
			(hide yes)
			(effects
				(font
					(size 1 1)
					(thickness 0.15)
				)
				(justify mirror)
			)
		)
		(property "License" "Apache-2.0"
			(at 154.790159 253.516183 0)
			(layer "B.Fab")
			(hide yes)
			(effects
				(font
					(size 1 1)
					(thickness 0.15)
				)
				(justify mirror)
			)
		)
		(property "MPN" "CC0201KRX6S5BB104"
			(at 154.790159 253.516183 0)
			(layer "B.Fab")
			(hide yes)
			(effects
				(font
					(size 1 1)
					(thickness 0.15)
				)
				(justify mirror)
			)
		)
		(property "Manufacturer" "YAGEO"
			(at 154.790159 253.516183 0)
			(layer "B.Fab")
			(hide yes)
			(effects
				(font
					(size 1 1)
					(thickness 0.15)
				)
				(justify mirror)
			)
		)
		(property "Val" "100n"
			(at 154.790159 253.516183 0)
			(layer "B.Fab")
			(hide yes)
			(effects
				(font
					(size 1 1)
					(thickness 0.15)
				)
				(justify mirror)
			)
		)
		(property "Voltage" ""
			(at 154.790159 253.516183 0)
			(layer "B.Fab")
			(hide yes)
			(effects
				(font
					(size 1 1)
					(thickness 0.15)
				)
				(justify mirror)
			)
		)
		(property "Public" "False"
			(at 0 0 225)
			(unlocked yes)
			(layer "B.Fab")
			(hide yes)
			(effects
				(font
					(size 1 1)
					(thickness 0.15)
				)
				(justify mirror)
			)
		)
		(sheetname "/FPGA Power/")
		(sheetfile "FPGA_Power.kicad_sch")
		(attr smd)
		(fp_poly
			(pts
				(xy -0.7 0.35) (xy 0.7 0.35) (xy 0.7 -0.35) (xy -0.7 -0.35)
			)
			(stroke
				(width 0.05)
				(type default)
			)
			(fill no)
			(layer "B.CrtYd")
		)
		(fp_poly
			(pts
				(xy 0.3 -0.15) (xy -0.301 -0.15) (xy -0.301 0.149) (xy 0.3 0.149)
			)
			(stroke
				(width 0.15)
				(type solid)
			)
			(fill no)
			(layer "B.Fab")
		)
		(fp_text user "License: Apache-2.0"
			(at -0.72 -4.4 45)
			(layer "B.Fab")
			(effects
				(font
					(size 0.7 0.7)
					(thickness 0.15)
				)
				(justify left bottom mirror)
			)
		)
		(fp_text user "${REFERENCE}"
			(at -0.72 -3.4 45)
			(layer "B.Fab")
			(effects
				(font
					(size 0.7 0.7)
					(thickness 0.15)
				)
				(justify left bottom mirror)
			)
		)
		(fp_text user "Author: Antmicro"
			(at -0.72 -5.400001 45)
			(layer "B.Fab")
			(effects
				(font
					(size 0.7 0.7)
					(thickness 0.15)
				)
				(justify left bottom mirror)
			)
		)
		(pad "" smd roundrect
			(at -0.349 0.002 225)
			(size 0.318 0.36)
			(layers "B.Paste")
			(roundrect_rratio 0.25)
		)
		(pad "" smd roundrect
			(at 0.341 0.002 225)
			(size 0.318 0.36)
			(layers "B.Paste")
			(roundrect_rratio 0.25)
		)
		(pad "1" smd roundrect
			(at -0.321 0.002 225)
			(size 0.46 0.4)
			(layers "B.Cu" "B.Mask")
			(roundrect_rratio 0.25)
			(net 1 "GND")
			(pintype "passive")
		)
		(pad "2" smd roundrect
			(at 0.32 0.002 225)
			(size 0.46 0.4)
			(layers "B.Cu" "B.Mask")
			(roundrect_rratio 0.25)
			(net 13 "/FPGA Power/VCC_PLLDPHY")
			(pintype "passive")
		)
	)
	(footprint "antmicro-footprints:C_0201"
		(layer "B.Cu")
		(at 131.1 92.3 -90)
		(descr "Capacitor SMD 0201")
		(tags "capacitor SMD 0201")
		(property "Reference" "C102"
			(at -13.945736 9.07 90)
			(layer "B.SilkS")
			(effects
				(font
					(size 0.65 0.65)
					(thickness 0.15)
				)
				(justify left bottom mirror)
			)
		)
		(property "Value" "C_100n_0201"
			(at 0 -1.4 90)
			(layer "B.Fab")
			(hide yes)
			(effects
				(font
					(size 0.7 0.7)
					(thickness 0.15)
				)
				(justify left bottom mirror)
			)
		)
		(property "Datasheet" "https://www.yageo.com/en/Chart/Download/pdf/CC0201KRX6S5BB104"
			(at 0 0 270)
			(layer "F.Fab")
			(hide yes)
			(effects
				(font
					(size 1.27 1.27)
					(thickness 0.15)
				)
			)
		)
		(property "Description" "SMD Multilayer Ceramic Capacitor, 0.1 µF, 6.3 V, 0201 [0603 Metric], ± 10%, X6S, CC Series"
			(at 0 0 270)
			(layer "F.Fab")
			(hide yes)
			(effects
				(font
					(size 1.27 1.27)
					(thickness 0.15)
				)
			)
		)
		(property "Author" "Antmicro"
			(at 38.8 223.4 0)
			(layer "B.Fab")
			(hide yes)
			(effects
				(font
					(size 1 1)
					(thickness 0.15)
				)
				(justify mirror)
			)
		)
		(property "Dielectric" ""
			(at 38.8 223.4 0)
			(layer "B.Fab")
			(hide yes)
			(effects
				(font
					(size 1 1)
					(thickness 0.15)
				)
				(justify mirror)
			)
		)
		(property "License" "Apache-2.0"
			(at 38.8 223.4 0)
			(layer "B.Fab")
			(hide yes)
			(effects
				(font
					(size 1 1)
					(thickness 0.15)
				)
				(justify mirror)
			)
		)
		(property "MPN" "CC0201KRX6S5BB104"
			(at 38.8 223.4 0)
			(layer "B.Fab")
			(hide yes)
			(effects
				(font
					(size 1 1)
					(thickness 0.15)
				)
				(justify mirror)
			)
		)
		(property "Manufacturer" "YAGEO"
			(at 38.8 223.4 0)
			(layer "B.Fab")
			(hide yes)
			(effects
				(font
					(size 1 1)
					(thickness 0.15)
				)
				(justify mirror)
			)
		)
		(property "Val" "100n"
			(at 38.8 223.4 0)
			(layer "B.Fab")
			(hide yes)
			(effects
				(font
					(size 1 1)
					(thickness 0.15)
				)
				(justify mirror)
			)
		)
		(property "Voltage" ""
			(at 38.8 223.4 0)
			(layer "B.Fab")
			(hide yes)
			(effects
				(font
					(size 1 1)
					(thickness 0.15)
				)
				(justify mirror)
			)
		)
		(property "Public" "False"
			(at 0 0 270)
			(unlocked yes)
			(layer "B.Fab")
			(hide yes)
			(effects
				(font
					(size 1 1)
					(thickness 0.15)
				)
				(justify mirror)
			)
		)
		(sheetname "/FPGA Power/")
		(sheetfile "FPGA_Power.kicad_sch")
		(attr smd)
		(fp_rect
			(start -0.7 0.35)
			(end 0.7 -0.35)
			(stroke
				(width 0.05)
				(type default)
			)
			(fill no)
			(layer "B.CrtYd")
		)
		(fp_rect
			(start 0.3 -0.15)
			(end -0.301 0.149)
			(stroke
				(width 0.15)
				(type solid)
			)
			(fill no)
			(layer "B.Fab")
		)
		(fp_text user "Author: Antmicro"
			(at -0.72 -5.4 90)
			(layer "B.Fab")
			(effects
				(font
					(size 0.7 0.7)
					(thickness 0.15)
				)
				(justify left bottom mirror)
			)
		)
		(fp_text user "${REFERENCE}"
			(at -0.72 -3.4 90)
			(layer "B.Fab")
			(effects
				(font
					(size 0.7 0.7)
					(thickness 0.15)
				)
				(justify left bottom mirror)
			)
		)
		(fp_text user "License: Apache-2.0"
			(at -0.72 -4.4 90)
			(layer "B.Fab")
			(effects
				(font
					(size 0.7 0.7)
					(thickness 0.15)
				)
				(justify left bottom mirror)
			)
		)
		(pad "" smd roundrect
			(at -0.349 0.002 270)
			(size 0.318 0.36)
			(layers "B.Paste")
			(roundrect_rratio 0.25)
		)
		(pad "" smd roundrect
			(at 0.341 0.002 270)
			(size 0.318 0.36)
			(layers "B.Paste")
			(roundrect_rratio 0.25)
		)
		(pad "1" smd roundrect
			(at -0.321 0.002 270)
			(size 0.46 0.4)
			(layers "B.Cu" "B.Mask")
			(roundrect_rratio 0.25)
			(net 1 "GND")
			(pintype "passive")
		)
		(pad "2" smd roundrect
			(at 0.32 0.002 270)
			(size 0.46 0.4)
			(layers "B.Cu" "B.Mask")
			(roundrect_rratio 0.25)
			(net 12 "/FPGA Power/VCC_ADPHY")
			(pintype "passive")
		)
	)
	(footprint "antmicro-footprints:R_0402_1005Metric"
		(layer "B.Cu")
		(at 152.23 60.25 -90)
		(descr "Resistor SMD 0402")
		(tags "resistor SMD 0402")
		(property "Reference" "R8"
			(at -0.91 -1.3 90)
			(layer "B.SilkS")
			(effects
				(font
					(size 0.65 0.65)
					(thickness 0.15)
				)
				(justify left bottom mirror)
			)
		)
		(property "Value" "R_5k1_0402"
			(at 0 -1.4 90)
			(layer "B.Fab")
			(hide yes)
			(effects
				(font
					(size 0.7 0.7)
					(thickness 0.15)
				)
				(justify left bottom mirror)
			)
		)
		(property "Datasheet" "https://www.bourns.com/docs/product-datasheets/cr.pdf"
			(at 0 0 270)
			(layer "F.Fab")
			(hide yes)
			(effects
				(font
					(size 1.27 1.27)
					(thickness 0.15)
				)
			)
		)
		(property "Description" "SMD Chip Resistor, 5.1 kohm, ± 1%, 63 mW, 0402 [1005 Metric], Thick Film, General Purpose"
			(at 0 0 270)
			(layer "F.Fab")
			(hide yes)
			(effects
				(font
					(size 1.27 1.27)
					(thickness 0.15)
				)
			)
		)
		(property "Author" "Antmicro"
			(at 91.98 212.48 0)
			(layer "B.Fab")
			(hide yes)
			(effects
				(font
					(size 1 1)
					(thickness 0.15)
				)
				(justify mirror)
			)
		)
		(property "License" "Apache-2.0"
			(at 91.98 212.48 0)
			(layer "B.Fab")
			(hide yes)
			(effects
				(font
					(size 1 1)
					(thickness 0.15)
				)
				(justify mirror)
			)
		)
		(property "MPN" "CR0402-FX-5101GLF"
			(at 91.98 212.48 0)
			(layer "B.Fab")
			(hide yes)
			(effects
				(font
					(size 1 1)
					(thickness 0.15)
				)
				(justify mirror)
			)
		)
		(property "Manufacturer" "Bourns"
			(at 91.98 212.48 0)
			(layer "B.Fab")
			(hide yes)
			(effects
				(font
					(size 1 1)
					(thickness 0.15)
				)
				(justify mirror)
			)
		)
		(property "Tolerance" "1%"
			(at 91.98 212.48 0)
			(layer "B.Fab")
			(hide yes)
			(effects
				(font
					(size 1 1)
					(thickness 0.15)
				)
				(justify mirror)
			)
		)
		(property "Val" "5k1"
			(at 91.98 212.48 0)
			(layer "B.Fab")
			(hide yes)
			(effects
				(font
					(size 1 1)
					(thickness 0.15)
				)
				(justify mirror)
			)
		)
		(sheetname "/Peripherals/")
		(sheetfile "peripherals.kicad_sch")
		(attr smd)
		(fp_rect
			(start -0.925 0.47)
			(end 0.925 -0.47)
			(stroke
				(width 0.05)
				(type default)
			)
			(fill no)
			(layer "B.CrtYd")
		)
		(fp_rect
			(start -0.5 0.25)
			(end 0.5 -0.25)
			(stroke
				(width 0.15)
				(type solid)
			)
			(fill no)
			(layer "B.Fab")
		)
		(fp_text user "${REFERENCE}"
			(at -0.95 -3.168 90)
			(layer "B.Fab")
			(effects
				(font
					(size 0.7 0.7)
					(thickness 0.15)
				)
				(justify left bottom mirror)
			)
		)
		(fp_text user "License: Apache-2.0"
			(at -0.95 -5.169 90)
			(layer "B.Fab")
			(effects
				(font
					(size 0.7 0.7)
					(thickness 0.15)
				)
				(justify left bottom mirror)
			)
		)
		(fp_text user "Author: Antmicro"
			(at -0.95 -4.169 90)
			(layer "B.Fab")
			(effects
				(font
					(size 0.7 0.7)
					(thickness 0.15)
				)
				(justify left bottom mirror)
			)
		)
		(pad "1" smd roundrect
			(at -0.48 0 270)
			(size 0.59 0.64)
			(layers "B.Cu" "B.Mask" "B.Paste")
			(roundrect_rratio 0.25)
			(net 1 "GND")
			(pintype "passive")
		)
		(pad "2" smd roundrect
			(at 0.48 0 270)
			(size 0.59 0.64)
			(layers "B.Cu" "B.Mask" "B.Paste")
			(roundrect_rratio 0.25)
			(net 350 "Net-(J1-CC_{2})")
			(pintype "passive")
		)
	)
	(footprint "antmicro-footprints:C_0603_1608Metric"
		(layer "B.Cu")
		(at 132.48 97.73)
		(descr "Capacitor SMD 0603")
		(tags "capacitor 0603")
		(property "Reference" "C91"
			(at -3.2 0.69 0)
			(layer "B.SilkS")
			(effects
				(font
					(size 0.65 0.65)
					(thickness 0.15)
				)
				(justify right bottom mirror)
			)
		)
		(property "Value" "C_10u_0603"
			(at 0 -1.6 0)
			(layer "B.Fab")
			(hide yes)
			(effects
				(font
					(size 0.7 0.7)
					(thickness 0.15)
				)
				(justify right bottom mirror)
			)
		)
		(property "Datasheet" "https://www.murata.com/products/productdetail?partno=GRM188R61A106KE69%23"
			(at 0 0 0)
			(layer "F.Fab")
			(hide yes)
			(effects
				(font
					(size 1.27 1.27)
					(thickness 0.15)
				)
			)
		)
		(property "Description" "SMD Multilayer Ceramic Capacitor, 10 µF, 10 V, 0603 [1608 Metric], ± 10%, X5R, GRM Series"
			(at 0 0 0)
			(layer "F.Fab")
			(hide yes)
			(effects
				(font
					(size 1.27 1.27)
					(thickness 0.15)
				)
			)
		)
		(property "Author" "Antmicro"
			(at 0 0 0)
			(layer "B.Fab")
			(hide yes)
			(effects
				(font
					(size 1 1)
					(thickness 0.15)
				)
				(justify mirror)
			)
		)
		(property "License" "Apache-2.0"
			(at 0 0 0)
			(layer "B.Fab")
			(hide yes)
			(effects
				(font
					(size 1 1)
					(thickness 0.15)
				)
				(justify mirror)
			)
		)
		(property "MPN" "GRM188R61A106KE69D"
			(at 0 0 0)
			(layer "B.Fab")
			(hide yes)
			(effects
				(font
					(size 1 1)
					(thickness 0.15)
				)
				(justify mirror)
			)
		)
		(property "Manufacturer" "Murata"
			(at 0 0 0)
			(layer "B.Fab")
			(hide yes)
			(effects
				(font
					(size 1 1)
					(thickness 0.15)
				)
				(justify mirror)
			)
		)
		(property "Val" "10u"
			(at 0 0 0)
			(layer "B.Fab")
			(hide yes)
			(effects
				(font
					(size 1 1)
					(thickness 0.15)
				)
				(justify mirror)
			)
		)
		(property "Voltage" ""
			(at 0 0 0)
			(layer "B.Fab")
			(hide yes)
			(effects
				(font
					(size 1 1)
					(thickness 0.15)
				)
				(justify mirror)
			)
		)
		(property "Dielectric" "template_dielectric"
			(at 0 0 0)
			(unlocked yes)
			(layer "B.Fab")
			(hide yes)
			(effects
				(font
					(size 1 1)
					(thickness 0.15)
				)
				(justify mirror)
			)
		)
		(sheetname "/FPGA Power/")
		(sheetfile "FPGA_Power.kicad_sch")
		(attr smd)
		(fp_line
			(start -0.15 -0.4)
			(end 0.15 -0.4)
			(stroke
				(width 0.15)
				(type solid)
			)
			(layer "B.SilkS")
		)
		(fp_line
			(start -0.15 0.4)
			(end 0.15 0.4)
			(stroke
				(width 0.15)
				(type solid)
			)
			(layer "B.SilkS")
		)
		(fp_rect
			(start -1.25 0.65)
			(end 1.25 -0.65)
			(stroke
				(width 0.05)
				(type solid)
			)
			(fill no)
			(layer "B.CrtYd")
		)
		(fp_rect
			(start -0.8 0.4)
			(end 0.8 -0.4)
			(stroke
				(width 0.15)
				(type solid)
			)
			(fill no)
			(layer "B.Fab")
		)
		(fp_text user "License: Apache-2.0"
			(at -1.682 -5.895 180)
			(layer "B.Fab")
			(effects
				(font
					(size 0.7 0.7)
					(thickness 0.15)
				)
				(justify left bottom mirror)
			)
		)
		(fp_text user "${REFERENCE}"
			(at -1.682 -3.895 180)
			(layer "B.Fab")
			(effects
				(font
					(size 0.7 0.7)
					(thickness 0.15)
				)
				(justify left bottom mirror)
			)
		)
		(fp_text user "Author: Antmicro"
			(at -1.682 -4.894 180)
			(layer "B.Fab")
			(effects
				(font
					(size 0.7 0.7)
					(thickness 0.15)
				)
				(justify left bottom mirror)
			)
		)
		(pad "1" smd roundrect
			(at -0.7 0)
			(size 0.8 1)
			(layers "B.Cu" "B.Mask" "B.Paste")
			(roundrect_rratio 0.2)
			(net 1 "GND")
			(pintype "passive")
		)
		(pad "2" smd roundrect
			(at 0.7 0)
			(size 0.8 1)
			(layers "B.Cu" "B.Mask" "B.Paste")
			(roundrect_rratio 0.2)
			(net 13 "/FPGA Power/VCC_PLLDPHY")
			(pintype "passive")
		)
	)
	(footprint "antmicro-footprints:TP_SMD_0.75mm"
		(layer "B.Cu")
		(at 98.44 88.2 90)
		(property "Reference" "TP29"
			(at 0.76 0.39 90)
			(layer "B.SilkS")
			(effects
				(font
					(size 0.65 0.65)
					(thickness 0.15)
				)
				(justify right bottom mirror)
			)
		)
		(property "Value" "TP_0.75mm_SMD"
			(at 0 -1.2 90)
			(layer "B.Fab")
			(hide yes)
			(effects
				(font
					(size 0.7 0.7)
					(thickness 0.15)
				)
				(justify right bottom mirror)
			)
		)
		(property "Description" "SMT test point"
			(at 0 0 90)
			(layer "F.Fab")
			(hide yes)
			(effects
				(font
					(size 1.27 1.27)
					(thickness 0.15)
				)
			)
		)
		(property "Author" "Antmicro"
			(at 186.64 -10.24 0)
			(layer "B.Fab")
			(hide yes)
			(effects
				(font
					(size 1 1)
					(thickness 0.15)
				)
				(justify mirror)
			)
		)
		(property "License" "Apache-2.0"
			(at 186.64 -10.24 0)
			(layer "B.Fab")
			(hide yes)
			(effects
				(font
					(size 1 1)
					(thickness 0.15)
				)
				(justify mirror)
			)
		)
		(property "MPN" ""
			(at 186.64 -10.24 0)
			(layer "B.Fab")
			(hide yes)
			(effects
				(font
					(size 1 1)
					(thickness 0.15)
				)
				(justify mirror)
			)
		)
		(property "Manufacturer" ""
			(at 186.64 -10.24 0)
			(layer "B.Fab")
			(hide yes)
			(effects
				(font
					(size 1 1)
					(thickness 0.15)
				)
				(justify mirror)
			)
		)
		(sheetname "/SDI/")
		(sheetfile "sdi.kicad_sch")
		(attr exclude_from_pos_files)
		(fp_circle
			(center 0 0)
			(end 0.475 0)
			(stroke
				(width 0.05)
				(type default)
			)
			(fill no)
			(layer "B.CrtYd")
		)
		(fp_text user "Author: Antmicro"
			(at -0.4 -3.901 270)
			(layer "B.Fab")
			(effects
				(font
					(size 0.7 0.7)
					(thickness 0.15)
				)
				(justify left bottom mirror)
			)
		)
		(fp_text user "License: Apache-2.0"
			(at -0.4 -5.101 270)
			(layer "B.Fab")
			(effects
				(font
					(size 0.7 0.7)
					(thickness 0.15)
				)
				(justify left bottom mirror)
			)
		)
		(fp_text user "${REFERENCE}"
			(at -0.4 -2.7 270)
			(layer "B.Fab")
			(effects
				(font
					(size 0.7 0.7)
					(thickness 0.15)
				)
				(justify left bottom mirror)
			)
		)
		(pad "1" smd circle
			(at 0 0 90)
			(size 0.75 0.75)
			(layers "B.Cu" "B.Mask")
			(net 201 "/SDI/~{SMPTE_BYPASS}")
			(pinfunction "1")
			(pintype "passive")
		)
	)
)
